(kicad_pcb
	(version 20241229)
	(generator "pcbnew")
	(generator_version "9.0")
	(general
		(thickness 1.6)
		(legacy_teardrops no)
	)
	(paper "A4")
	(title_block
		(title "OCuLink to PCIe adapter")
		(date "2025-06-18")
		(rev "1.0.0")
		(company "Antmicro Ltd")
		(comment 1 "www.antmicro.com")
		(comment 9 "footprints 141-145 of 159")
	)
	(layers
		(0 "F.Cu" signal)
		(4 "In1.Cu" signal)
		(6 "In2.Cu" signal)
		(2 "B.Cu" signal)
		(9 "F.Adhes" user "F.Adhesive")
		(11 "B.Adhes" user "B.Adhesive")
		(13 "F.Paste" user)
		(15 "B.Paste" user)
		(5 "F.SilkS" user "F.Silkscreen")
		(7 "B.SilkS" user "B.Silkscreen")
		(1 "F.Mask" user)
		(3 "B.Mask" user)
		(17 "Dwgs.User" user "User.Drawings")
		(19 "Cmts.User" user "User.Comments")
		(21 "Eco1.User" user "User.Eco1")
		(23 "Eco2.User" user "User.Eco2")
		(25 "Edge.Cuts" user)
		(27 "Margin" user)
		(31 "F.CrtYd" user "F.Courtyard")
		(29 "B.CrtYd" user "B.Courtyard")
		(35 "F.Fab" user)
		(33 "B.Fab" user)
	)
	(footprint "antmicro-footprints:C_0402_1005Metric"
		(layer "F.Cu")
		(at 138.499999 108.85 -90)
		(descr "Capacitor SMD 0402")
		(tags "capacitor SMD 0402")
		(property "Reference" "C33"
			(at 0.95 0.499999 90)
			(layer "F.SilkS")
			(effects
				(font
					(size 0.7 0.7)
					(thickness 0.15)
				)
				(justify right top)
			)
		)
		(property "Value" "C_1u_25V_0402"
			(at -1.022927 2.155213 90)
			(layer "F.Fab")
			(effects
				(font
					(size 0.7 0.7)
					(thickness 0.15)
				)
				(justify right top)
			)
		)
		(property "Datasheet" "https://www.murata.com/products/productdetail?partno=GRM155R61E105KE11%23"
			(at 0 0 90)
			(layer "F.Fab")
			(hide yes)
			(effects
				(font
					(size 1.27 1.27)
					(thickness 0.15)
				)
			)
		)
		(property "Description" "SMD Multilayer Ceramic Capacitor, 1 µF, 25 V, 0402 [1005 Metric], ± 10%, X5R, GRM Series"
			(at 0 0 90)
			(layer "F.Fab")
			(hide yes)
			(effects
				(font
					(size 1.27 1.27)
					(thickness 0.15)
				)
			)
		)
		(property "MPN" "GRM155R61E105KE11J"
			(at 0 0 270)
			(unlocked yes)
			(layer "F.Fab")
			(hide yes)
			(effects
				(font
					(size 1 1)
					(thickness 0.15)
				)
			)
		)
		(property "Manufacturer" "Murata"
			(at 0 0 270)
			(unlocked yes)
			(layer "F.Fab")
			(hide yes)
			(effects
				(font
					(size 1 1)
					(thickness 0.15)
				)
			)
		)
		(property "License" "Apache-2.0"
			(at 0 0 270)
			(unlocked yes)
			(layer "F.Fab")
			(hide yes)
			(effects
				(font
					(size 1 1)
					(thickness 0.15)
				)
			)
		)
		(property "Author" "Antmicro"
			(at 0 0 270)
			(unlocked yes)
			(layer "F.Fab")
			(hide yes)
			(effects
				(font
					(size 1 1)
					(thickness 0.15)
				)
			)
		)
		(property "Val" "1u"
			(at 0 0 270)
			(unlocked yes)
			(layer "F.Fab")
			(hide yes)
			(effects
				(font
					(size 1 1)
					(thickness 0.15)
				)
			)
		)
		(property "Voltage" "25V"
			(at 0 0 270)
			(unlocked yes)
			(layer "F.Fab")
			(hide yes)
			(effects
				(font
					(size 1 1)
					(thickness 0.15)
				)
			)
		)
		(property "Dielectric" "X5R"
			(at 0 0 270)
			(unlocked yes)
			(layer "F.Fab")
			(hide yes)
			(effects
				(font
					(size 1 1)
					(thickness 0.15)
				)
			)
		)
		(sheetname "/Power/Ideal-diode-0/")
		(sheetfile "ideal-diode.kicad_sch")
		(attr smd)
		(fp_rect
			(start -0.925 -0.47)
			(end 0.925 0.47)
			(stroke
				(width 0.05)
				(type default)
			)
			(fill no)
			(layer "F.CrtYd")
		)
		(fp_line
			(start -0.494 0.248)
			(end -0.494 -0.25)
			(stroke
				(width 0.15)
				(type solid)
			)
			(layer "F.Fab")
		)
		(fp_line
			(start 0.504 0.248)
			(end -0.494 0.248)
			(stroke
				(width 0.15)
				(type solid)
			)
			(layer "F.Fab")
		)
		(fp_line
			(start -0.494 -0.25)
			(end 0.504 -0.25)
			(stroke
				(width 0.15)
				(type solid)
			)
			(layer "F.Fab")
		)
		(fp_line
			(start 0.504 -0.25)
			(end 0.504 0.248)
			(stroke
				(width 0.15)
				(type solid)
			)
			(layer "F.Fab")
		)
		(fp_text user "Author: Antmicro"
			(at -0.939 3.399 90)
			(layer "F.Fab")
			(effects
				(font
					(size 0.7 0.7)
					(thickness 0.15)
				)
				(justify right top)
			)
		)
		(fp_text user "${REFERENCE}"
			(at 0 0 90)
			(layer "F.Fab")
			(effects
				(font
					(size 0.7 0.7)
					(thickness 0.15)
				)
				(justify right top)
			)
		)
		(fp_text user "License: Apache-2.0"
			(at -0.939 5.799 90)
			(layer "F.Fab")
			(effects
				(font
					(size 0.7 0.7)
					(thickness 0.15)
				)
				(justify right top)
			)
		)
		(pad "1" smd roundrect
			(at -0.48 0 270)
			(size 0.59 0.64)
			(layers "F.Cu" "F.Mask" "F.Paste")
			(roundrect_rratio 0.25)
			(net 66 "GND")
			(pintype "passive")
		)
		(pad "2" smd roundrect
			(at 0.48 0 270)
			(size 0.59 0.64)
			(layers "F.Cu" "F.Mask" "F.Paste")
			(roundrect_rratio 0.25)
			(net 87 "+12V")
			(pintype "passive")
		)
	)
	(footprint "antmicro-footprints:R_0603_1608Metric"
		(layer "F.Cu")
		(at 146.5 124.5 180)
		(descr "Resistor SMD 0603")
		(tags "resistor SMD 0603")
		(property "Reference" "R45"
			(at 1 -1.5 0)
			(layer "F.SilkS")
			(effects
				(font
					(size 0.7 0.7)
					(thickness 0.15)
				)
				(justify left bottom)
			)
		)
		(property "Value" "R_0R_22.4A_0603"
			(at 0 1.6 0)
			(layer "F.Fab")
			(effects
				(font
					(size 0.7 0.7)
					(thickness 0.15)
				)
				(justify right top)
			)
		)
		(property "Datasheet" "https://fscdn.rohm.com/en/products/databook/datasheet/passive/resistor/chip_resistor/pmr-jpw-e.pdf"
			(at 0 0 0)
			(layer "F.Fab")
			(hide yes)
			(effects
				(font
					(size 1.27 1.27)
					(thickness 0.15)
				)
			)
		)
		(property "Description" "SMD Chip Resistor"
			(at 0 0 0)
			(layer "F.Fab")
			(hide yes)
			(effects
				(font
					(size 1.27 1.27)
					(thickness 0.15)
				)
			)
		)
		(property "MPN" "PMR03EZPJ000"
			(at 0 0 180)
			(unlocked yes)
			(layer "F.Fab")
			(hide yes)
			(effects
				(font
					(size 1 1)
					(thickness 0.15)
				)
			)
		)
		(property "Manufacturer" "ROHM Semiconductor"
			(at 0 0 180)
			(unlocked yes)
			(layer "F.Fab")
			(hide yes)
			(effects
				(font
					(size 1 1)
					(thickness 0.15)
				)
			)
		)
		(property "Val" "0R"
			(at 0 0 180)
			(unlocked yes)
			(layer "F.Fab")
			(hide yes)
			(effects
				(font
					(size 1 1)
					(thickness 0.15)
				)
			)
		)
		(property "Max. Curr." "22.4A"
			(at 0 0 180)
			(unlocked yes)
			(layer "F.Fab")
			(hide yes)
			(effects
				(font
					(size 1 1)
					(thickness 0.15)
				)
			)
		)
		(property "Author" "Antmicro"
			(at 0 0 180)
			(unlocked yes)
			(layer "F.Fab")
			(hide yes)
			(effects
				(font
					(size 1 1)
					(thickness 0.15)
				)
			)
		)
		(property "License" "Apache-2.0"
			(at 0 0 180)
			(unlocked yes)
			(layer "F.Fab")
			(hide yes)
			(effects
				(font
					(size 1 1)
					(thickness 0.15)
				)
			)
		)
		(property "Tolerance" "template_tolerance"
			(at 0 0 180)
			(unlocked yes)
			(layer "F.Fab")
			(hide yes)
			(effects
				(font
					(size 1 1)
					(thickness 0.15)
				)
			)
		)
		(sheetname "/")
		(sheetfile "oculink-to-pcie-adapter.kicad_sch")
		(attr smd exclude_from_bom dnp)
		(fp_line
			(start -0.15 0.4)
			(end 0.15 0.4)
			(stroke
				(width 0.15)
				(type solid)
			)
			(layer "F.SilkS")
		)
		(fp_line
			(start -0.15 -0.4)
			(end 0.15 -0.4)
			(stroke
				(width 0.15)
				(type solid)
			)
			(layer "F.SilkS")
		)
		(fp_rect
			(start -1.25 -0.65)
			(end 1.25 0.65)
			(stroke
				(width 0.05)
				(type solid)
			)
			(fill no)
			(layer "F.CrtYd")
		)
		(fp_rect
			(start -0.8 -0.4)
			(end 0.8 0.4)
			(stroke
				(width 0.15)
				(type solid)
			)
			(fill no)
			(layer "F.Fab")
		)
		(fp_text user "License: Apache-2.0"
			(at -1.249999 5.9 0)
			(layer "F.Fab")
			(effects
				(font
					(size 0.7 0.7)
					(thickness 0.15)
				)
				(justify right top)
			)
		)
		(fp_text user "Author: Antmicro"
			(at -1.25 4.9 0)
			(layer "F.Fab")
			(effects
				(font
					(size 0.7 0.7)
					(thickness 0.15)
				)
				(justify right top)
			)
		)
		(fp_text user "${REFERENCE}"
			(at 0 0 0)
			(layer "F.Fab")
			(effects
				(font
					(size 0.7 0.7)
					(thickness 0.15)
				)
				(justify right top)
			)
		)
		(pad "1" smd roundrect
			(at -0.7 0 180)
			(size 0.8 1)
			(layers "F.Cu" "F.Mask" "F.Paste")
			(roundrect_rratio 0.2)
			(net 169 "/Power/VCC_DC_CONN_2")
			(pintype "passive")
		)
		(pad "2" smd roundrect
			(at 0.7 0 180)
			(size 0.8 1)
			(layers "F.Cu" "F.Mask" "F.Paste")
			(roundrect_rratio 0.2)
			(net 168 "/Power/VCC_DC_CONN_1")
			(pintype "passive")
		)
	)
	(footprint "antmicro-footprints:Mech_Lightpipe_Mentor_1296.2013"
		(layer "F.Cu")
		(at 151.5 159.71 180)
		(property "Reference" "H1"
			(at 0 -0.499999 270)
			(layer "F.SilkS")
			(hide yes)
			(effects
				(font
					(size 0.7 0.7)
					(thickness 0.15)
				)
				(justify left bottom)
			)
		)
		(property "Value" "Lightpipe_Mentor_1296.2013"
			(at -1.749999 6.25 180)
			(unlocked yes)
			(layer "F.Fab")
			(effects
				(font
					(size 0.7 0.7)
					(thickness 0.15)
				)
				(justify left bottom)
			)
		)
		(property "Datasheet" "https://docs.rs-online.com/e47b/0900766b813f6efb.pdf"
			(at 0 0 0)
			(layer "F.Fab")
			(hide yes)
			(effects
				(font
					(size 1.27 1.27)
					(thickness 0.15)
				)
			)
		)
		(property "Description" "Light Pipe, Miniature Triple Line, 14.45 mm, 3 Pipes, Circular, PC Board, Transparent"
			(at 0 0 0)
			(layer "F.Fab")
			(hide yes)
			(effects
				(font
					(size 1.27 1.27)
					(thickness 0.15)
				)
			)
		)
		(property "Manufacturer" "Mentor Worldwide"
			(at 0 0 180)
			(unlocked yes)
			(layer "F.Fab")
			(hide yes)
			(effects
				(font
					(size 1 1)
					(thickness 0.15)
				)
			)
		)
		(property "MPN" "1296.2013"
			(at 0 0 180)
			(unlocked yes)
			(layer "F.Fab")
			(hide yes)
			(effects
				(font
					(size 1 1)
					(thickness 0.15)
				)
			)
		)
		(property "Author" "Antmicro"
			(at 0 0 180)
			(unlocked yes)
			(layer "F.Fab")
			(hide yes)
			(effects
				(font
					(size 1 1)
					(thickness 0.15)
				)
			)
		)
		(property "License" "Apache-2.0"
			(at 0 0 180)
			(unlocked yes)
			(layer "F.Fab")
			(hide yes)
			(effects
				(font
					(size 1 1)
					(thickness 0.15)
				)
			)
		)
		(sheetname "/Power/")
		(sheetfile "power.kicad_sch")
		(attr dnp)
		(fp_rect
			(start -1.508 -6.335)
			(end 1.507 5.289)
			(stroke
				(width 0.15)
				(type solid)
			)
			(fill no)
			(layer "F.SilkS")
		)
		(fp_text user "Author: Antmicro"
			(at -1.75 8.75 0)
			(layer "F.Fab")
			(effects
				(font
					(size 0.7 0.7)
					(thickness 0.15)
				)
				(justify right top)
			)
		)
		(fp_text user "${REFERENCE}"
			(at -1.75 7.5 0)
			(layer "F.Fab")
			(effects
				(font
					(size 0.7 0.7)
					(thickness 0.15)
				)
				(justify right top)
			)
		)
		(fp_text user "License: Apache-2.0"
			(at -1.749999 10.25 0)
			(layer "F.Fab")
			(effects
				(font
					(size 0.7 0.7)
					(thickness 0.15)
				)
				(justify right top)
			)
		)
		(pad "" np_thru_hole circle
			(at 0 -4.96 180)
			(size 1.2 1.2)
			(drill 1.2)
			(layers "F&B.Cu" "*.Mask")
		)
		(pad "" np_thru_hole circle
			(at 0 4.24 180)
			(size 1.2 1.2)
			(drill 1.2)
			(layers "F&B.Cu" "*.Mask")
		)
	)
	(footprint "antmicro-footprints:R_0402_1005Metric"
		(layer "F.Cu")
		(at 148.152 87)
		(descr "Resistor SMD 0402")
		(tags "resistor SMD 0402")
		(property "Reference" "R32"
			(at 1.248 0.3 180)
			(layer "F.SilkS")
			(effects
				(font
					(size 0.7 0.7)
					(thickness 0.15)
				)
				(justify left bottom)
			)
		)
		(property "Value" "R_100k_0402"
			(at -1.011843 1.772046 0)
			(layer "F.Fab")
			(effects
				(font
					(size 0.7 0.7)
					(thickness 0.15)
				)
				(justify left bottom)
			)
		)
		(property "Datasheet" "https://www.bourns.com/docs/product-datasheets/cr.pdf"
			(at 0 0 0)
			(layer "F.Fab")
			(hide yes)
			(effects
				(font
					(size 1.27 1.27)
					(thickness 0.15)
				)
			)
		)
		(property "Description" "SMD Chip Resistor, 100 kohm, ± 1%, 62.5 mW, 0402 [1005 Metric], Thick Film, General Purpose"
			(at 0 0 0)
			(layer "F.Fab")
			(hide yes)
			(effects
				(font
					(size 1.27 1.27)
					(thickness 0.15)
				)
			)
		)
		(property "Manufacturer" "Bourns"
			(at 0 0 0)
			(unlocked yes)
			(layer "F.Fab")
			(hide yes)
			(effects
				(font
					(size 1 1)
					(thickness 0.15)
				)
			)
		)
		(property "MPN" "CR0402-FX-1003GLF"
			(at 0 0 0)
			(unlocked yes)
			(layer "F.Fab")
			(hide yes)
			(effects
				(font
					(size 1 1)
					(thickness 0.15)
				)
			)
		)
		(property "Val" "100k"
			(at 0 0 0)
			(unlocked yes)
			(layer "F.Fab")
			(hide yes)
			(effects
				(font
					(size 1 1)
					(thickness 0.15)
				)
			)
		)
		(property "License" "Apache-2.0"
			(at 0 0 0)
			(unlocked yes)
			(layer "F.Fab")
			(hide yes)
			(effects
				(font
					(size 1 1)
					(thickness 0.15)
				)
			)
		)
		(property "Author" "Antmicro"
			(at 0 0 0)
			(unlocked yes)
			(layer "F.Fab")
			(hide yes)
			(effects
				(font
					(size 1 1)
					(thickness 0.15)
				)
			)
		)
		(property "Tolerance" "1%"
			(at 0 0 0)
			(unlocked yes)
			(layer "F.Fab")
			(hide yes)
			(effects
				(font
					(size 1 1)
					(thickness 0.15)
				)
			)
		)
		(sheetname "/USB-PD/")
		(sheetfile "usb-pd.kicad_sch")
		(attr smd)
		(fp_rect
			(start -0.925 -0.47)
			(end 0.925 0.47)
			(stroke
				(width 0.05)
				(type default)
			)
			(fill no)
			(layer "F.CrtYd")
		)
		(fp_rect
			(start -0.5 -0.25)
			(end 0.5 0.25)
			(stroke
				(width 0.15)
				(type solid)
			)
			(fill no)
			(layer "F.Fab")
		)
		(fp_text user "License: Apache-2.0"
			(at -0.949999 5.169 0)
			(layer "F.Fab")
			(effects
				(font
					(size 0.7 0.7)
					(thickness 0.15)
				)
				(justify left bottom)
			)
		)
		(fp_text user "${REFERENCE}"
			(at 0 0 0)
			(layer "F.Fab")
			(effects
				(font
					(size 0.7 0.7)
					(thickness 0.15)
				)
				(justify left bottom)
			)
		)
		(fp_text user "Author: Antmicro"
			(at -0.95 4.169 0)
			(layer "F.Fab")
			(effects
				(font
					(size 0.7 0.7)
					(thickness 0.15)
				)
				(justify left bottom)
			)
		)
		(pad "1" smd roundrect
			(at -0.48 0)
			(size 0.59 0.64)
			(layers "F.Cu" "F.Mask" "F.Paste")
			(roundrect_rratio 0.25)
			(net 156 "/USB-PD/12V_EN")
			(pintype "passive")
		)
		(pad "2" smd roundrect
			(at 0.48 0)
			(size 0.59 0.64)
			(layers "F.Cu" "F.Mask" "F.Paste")
			(roundrect_rratio 0.25)
			(net 115 "/USB-PD/VCC")
			(pintype "passive")
		)
	)
	(footprint "antmicro-footprints:R_0402_1005Metric"
		(layer "F.Cu")
		(at 148.152 91 180)
		(descr "Resistor SMD 0402")
		(tags "resistor SMD 0402")
		(property "Reference" "R30"
			(at -3.448 0.5 180)
			(layer "F.SilkS")
			(effects
				(font
					(size 0.7 0.7)
					(thickness 0.15)
				)
				(justify right top)
			)
		)
		(property "Value" "R_0R_0402"
			(at -1.011843 1.772046 0)
			(layer "F.Fab")
			(effects
				(font
					(size 0.7 0.7)
					(thickness 0.15)
				)
				(justify right top)
			)
		)
		(property "Datasheet" "https://industrial.panasonic.com/cdbs/www-data/pdf/RDA0000/AOA0000C301.pdf"
			(at 0 0 0)
			(layer "F.Fab")
			(hide yes)
			(effects
				(font
					(size 1.27 1.27)
					(thickness 0.15)
				)
			)
		)
		(property "Description" "SMD Chip Resistor, Jumper, 0 ohm, 100 mW, 0402 [1005 Metric], Thick Film, General Purpose"
			(at 0 0 0)
			(layer "F.Fab")
			(hide yes)
			(effects
				(font
					(size 1.27 1.27)
					(thickness 0.15)
				)
			)
		)
		(property "Manufacturer" "Panasonic"
			(at 0 0 180)
			(unlocked yes)
			(layer "F.Fab")
			(hide yes)
			(effects
				(font
					(size 1 1)
					(thickness 0.15)
				)
			)
		)
		(property "MPN" "ERJ2GE0R00X"
			(at 0 0 180)
			(unlocked yes)
			(layer "F.Fab")
			(hide yes)
			(effects
				(font
					(size 1 1)
					(thickness 0.15)
				)
			)
		)
		(property "Val" "0R"
			(at 0 0 180)
			(unlocked yes)
			(layer "F.Fab")
			(hide yes)
			(effects
				(font
					(size 1 1)
					(thickness 0.15)
				)
			)
		)
		(property "License" "Apache-2.0"
			(at 0 0 180)
			(unlocked yes)
			(layer "F.Fab")
			(hide yes)
			(effects
				(font
					(size 1 1)
					(thickness 0.15)
				)
			)
		)
		(property "Author" "Antmicro"
			(at 0 0 180)
			(unlocked yes)
			(layer "F.Fab")
			(hide yes)
			(effects
				(font
					(size 1 1)
					(thickness 0.15)
				)
			)
		)
		(property "Tolerance" ""
			(at 0 0 180)
			(unlocked yes)
			(layer "F.Fab")
			(hide yes)
			(effects
				(font
					(size 1 1)
					(thickness 0.15)
				)
			)
		)
		(property "Current" "1A"
			(at 0 0 180)
			(unlocked yes)
			(layer "F.Fab")
			(hide yes)
			(effects
				(font
					(size 1 1)
					(thickness 0.15)
				)
			)
		)
		(sheetname "/USB-PD/")
		(sheetfile "usb-pd.kicad_sch")
		(attr smd)
		(fp_rect
			(start -0.925 -0.47)
			(end 0.925 0.47)
			(stroke
				(width 0.05)
				(type default)
			)
			(fill no)
			(layer "F.CrtYd")
		)
		(fp_rect
			(start -0.5 -0.25)
			(end 0.5 0.25)
			(stroke
				(width 0.15)
				(type solid)
			)
			(fill no)
			(layer "F.Fab")
		)
		(fp_text user "Author: Antmicro"
			(at -0.95 4.169 0)
			(layer "F.Fab")
			(effects
				(font
					(size 0.7 0.7)
					(thickness 0.15)
				)
				(justify right top)
			)
		)
		(fp_text user "License: Apache-2.0"
			(at -0.949999 5.169 0)
			(layer "F.Fab")
			(effects
				(font
					(size 0.7 0.7)
					(thickness 0.15)
				)
				(justify right top)
			)
		)
		(fp_text user "${REFERENCE}"
			(at 0 0 0)
			(layer "F.Fab")
			(effects
				(font
					(size 0.7 0.7)
					(thickness 0.15)
				)
				(justify right top)
			)
		)
		(pad "1" smd roundrect
			(at -0.48 0 180)
			(size 0.59 0.64)
			(layers "F.Cu" "F.Mask" "F.Paste")
			(roundrect_rratio 0.25)
			(net 121 "/USB-PD/12V_VDD")
			(pintype "passive")
		)
		(pad "2" smd roundrect
			(at 0.48 0 180)
			(size 0.59 0.64)
			(layers "F.Cu" "F.Mask" "F.Paste")
			(roundrect_rratio 0.25)
			(net 155 "/USB-PD/12V_ILIM")
			(pintype "passive")
		)
	)
)
